(kicad_pcb
	(version 20260206)
	(generator "pcbnew")
	(generator_version "10.0")
	(general
		(thickness 1.6)
		(legacy_teardrops no)
	)
	(paper "A4")
	(title_block
		(title "panther-plus-userver — 13130-1b_20150205.brd")
		(comment 1 "Honey Badger (Wiwynn) / footprints 34-41 of 1509")
	)
	(layers
		(0 "F.Cu" signal "TOP")
		(4 "In1.Cu" signal "L2")
		(6 "In2.Cu" signal "L3")
		(8 "In3.Cu" signal "L4")
		(10 "In4.Cu" signal "L5")
		(12 "In5.Cu" signal "L6")
		(14 "In6.Cu" signal "L7")
		(16 "In7.Cu" signal "L8")
		(18 "In8.Cu" signal "L9")
		(20 "In9.Cu" signal "L10")
		(22 "In10.Cu" signal "L11")
		(2 "B.Cu" signal "BOTTOM")
		(9 "F.Adhes" user "F.Adhesive")
		(11 "B.Adhes" user "B.Adhesive")
		(13 "F.Paste" user "Package Geometry/Pastemask Top")
		(15 "B.Paste" user "Package Geometry/Pastemask Bottom")
		(5 "F.SilkS" user "Ref Des/Silkscreen Top")
		(7 "B.SilkS" user "Ref Des/Silkscreen Bottom")
		(1 "F.Mask" user "Board Geometry/Soldermask Top")
		(3 "B.Mask" user "Board Geometry/Soldermask Bottom")
		(17 "Dwgs.User" user "User.Drawings")
		(19 "Cmts.User" user "User.Comments")
		(21 "Eco1.User" user "User.Eco1")
		(23 "Eco2.User" user "User.Eco2")
		(25 "Edge.Cuts" user "Board Geometry/Outline")
		(27 "Margin" user)
		(31 "F.CrtYd" user "Package Geometry/Place Bound Top")
		(29 "B.CrtYd" user "Package Geometry/Place Bound Bottom")
		(35 "F.Fab" user "Ref Des/Assembly Top")
		(33 "B.Fab" user "Ref Des/Assembly Bottom")
	)
	(footprint ""
		(layer "F.Cu")
		(at 26.289 -32.385 180)
		(property "Reference" "PC51"
			(at 0 0 180)
			(layer "F.SilkS")
			(hide yes)
			(effects
				(font
					(size 1.27 1.27)
				)
			)
		)
		(property "Value" "SC22U6D3V3MX-1-GP"
			(at -0.0254 -2.0193 180)
			(unlocked yes)
			(layer "F.Fab")
			(hide yes)
			(effects
				(font
					(size 1.016 1.016)
					(thickness 0.1524)
				)
			)
		)
		(property "Device Type" "C603H40"
			(at -0.0254 -3.5433 180)
			(unlocked yes)
			(layer "F.Fab")
			(hide yes)
			(effects
				(font
					(size 1.016 1.016)
					(thickness 0.1524)
				)
			)
		)
		(duplicate_pad_numbers_are_jumpers no)
		(fp_line
			(start -0.4064 0)
			(end 0.4064 0)
			(stroke
				(width 0.2286)
				(type default)
			)
			(layer "F.SilkS")
		)
		(fp_rect
			(start -0.635 1.1811)
			(end 0.635 -1.1811)
			(stroke
				(width 0)
				(type default)
			)
			(fill no)
			(layer "F.CrtYd")
		)
		(fp_rect
			(start -0.635 1.1811)
			(end 0.635 -1.1811)
			(stroke
				(width 0)
				(type default)
			)
			(fill no)
			(layer "F.Fab")
		)
		(pad "1" smd custom
			(at 0 -0.6604 180)
			(size 0.19685 0.19685)
			(layers "F.Cu" "F.Mask" "F.Paste")
			(net "P1V0")
			(options
				(clearance outline)
				(anchor circle)
			)
			(primitives
				(gr_poly
					(pts
						(arc
							(start 0.508 -0.2921)
							(mid 0.478242 -0.363942)
							(end 0.4064 -0.3937)
						)
						(arc
							(start -0.4064 -0.3937)
							(mid -0.478242 -0.363942)
							(end -0.508 -0.2921)
						)
						(arc
							(start -0.508 0.2921)
							(mid -0.478242 0.363942)
							(end -0.4064 0.3937)
						)
						(arc
							(start 0.4064 0.3937)
							(mid 0.478242 0.363942)
							(end 0.508 0.2921)
						)
					)
					(width 0)
					(fill yes)
				)
			)
		)
		(pad "2" smd custom
			(at 0 0.6604 180)
			(size 0.19685 0.19685)
			(layers "F.Cu" "F.Mask" "F.Paste")
			(net "GND")
			(options
				(clearance outline)
				(anchor circle)
			)
			(primitives
				(gr_poly
					(pts
						(arc
							(start 0.508 -0.2921)
							(mid 0.478242 -0.363942)
							(end 0.4064 -0.3937)
						)
						(arc
							(start -0.4064 -0.3937)
							(mid -0.478242 -0.363942)
							(end -0.508 -0.2921)
						)
						(arc
							(start -0.508 0.2921)
							(mid -0.478242 0.363942)
							(end -0.4064 0.3937)
						)
						(arc
							(start 0.4064 0.3937)
							(mid 0.478242 0.363942)
							(end 0.508 0.2921)
						)
					)
					(width 0)
					(fill yes)
				)
			)
		)
	)
	(footprint ""
		(layer "F.Cu")
		(at 173.355 -57.15 180)
		(property "Reference" "R185"
			(at 0 0 180)
			(layer "F.SilkS")
			(hide yes)
			(effects
				(font
					(size 1.27 1.27)
				)
			)
		)
		(property "Value" "4K7R2F-GP"
			(at 0.064008 -3.993896 180)
			(unlocked yes)
			(layer "F.Fab")
			(hide yes)
			(effects
				(font
					(size 1.016 1.016)
					(thickness 0.1524)
				)
			)
		)
		(property "Device Type" "R402H16"
			(at 0.064008 -5.517896 180)
			(unlocked yes)
			(layer "F.Fab")
			(hide yes)
			(effects
				(font
					(size 1.016 1.016)
					(thickness 0.1524)
				)
			)
		)
		(duplicate_pad_numbers_are_jumpers no)
		(fp_rect
			(start -0.381 0.8382)
			(end 0.381 -0.8382)
			(stroke
				(width 0)
				(type default)
			)
			(fill no)
			(layer "F.CrtYd")
		)
		(fp_rect
			(start -0.381 0.8382)
			(end 0.381 -0.8382)
			(stroke
				(width 0)
				(type default)
			)
			(fill no)
			(layer "F.Fab")
		)
		(pad "1" smd custom
			(at 0 -0.4318 180)
			(size 0.127 0.127)
			(layers "F.Cu" "F.Mask" "F.Paste")
			(net "EEPROM_A2")
			(options
				(clearance outline)
				(anchor circle)
			)
			(primitives
				(gr_poly
					(pts
						(arc
							(start -0.2032 -0.2794)
							(mid -0.239121 -0.264521)
							(end -0.254 -0.2286)
						)
						(arc
							(start -0.254 0.2286)
							(mid -0.239121 0.264521)
							(end -0.2032 0.2794)
						)
						(arc
							(start 0.2032 0.2794)
							(mid 0.239121 0.264521)
							(end 0.254 0.2286)
						)
						(arc
							(start 0.254 -0.2286)
							(mid 0.239121 -0.264521)
							(end 0.2032 -0.2794)
						)
					)
					(width 0)
					(fill yes)
				)
			)
		)
		(pad "2" smd custom
			(at 0 0.4318 180)
			(size 0.127 0.127)
			(layers "F.Cu" "F.Mask" "F.Paste")
			(net "GND")
			(options
				(clearance outline)
				(anchor circle)
			)
			(primitives
				(gr_poly
					(pts
						(arc
							(start -0.2032 -0.2794)
							(mid -0.239121 -0.264521)
							(end -0.254 -0.2286)
						)
						(arc
							(start -0.254 0.2286)
							(mid -0.239121 0.264521)
							(end -0.2032 0.2794)
						)
						(arc
							(start 0.2032 0.2794)
							(mid 0.239121 0.264521)
							(end 0.254 0.2286)
						)
						(arc
							(start 0.254 -0.2286)
							(mid 0.239121 -0.264521)
							(end 0.2032 -0.2794)
						)
					)
					(width 0)
					(fill yes)
				)
			)
		)
	)
	(footprint ""
		(layer "F.Cu")
		(at 198.12 -4.826 90)
		(property "Reference" "R389"
			(at 0 0 90)
			(layer "F.SilkS")
			(hide yes)
			(effects
				(font
					(size 1.27 1.27)
				)
			)
		)
		(property "Value" "4K7R2F-GP"
			(at 0.064008 -3.993896 90)
			(unlocked yes)
			(layer "F.Fab")
			(hide yes)
			(effects
				(font
					(size 1.016 1.016)
					(thickness 0.1524)
				)
			)
		)
		(property "Device Type" "R402H16"
			(at 0.064008 -5.517896 90)
			(unlocked yes)
			(layer "F.Fab")
			(hide yes)
			(effects
				(font
					(size 1.016 1.016)
					(thickness 0.1524)
				)
			)
		)
		(duplicate_pad_numbers_are_jumpers no)
		(fp_rect
			(start -0.381 0.8382)
			(end 0.381 -0.8382)
			(stroke
				(width 0)
				(type default)
			)
			(fill no)
			(layer "F.CrtYd")
		)
		(fp_rect
			(start -0.381 0.8382)
			(end 0.381 -0.8382)
			(stroke
				(width 0)
				(type default)
			)
			(fill no)
			(layer "F.Fab")
		)
		(pad "1" smd custom
			(at 0 -0.4318 90)
			(size 0.127 0.127)
			(layers "F.Cu" "F.Mask" "F.Paste")
			(net "CHB_1_SA1")
			(options
				(clearance outline)
				(anchor circle)
			)
			(primitives
				(gr_poly
					(pts
						(arc
							(start -0.2032 -0.2794)
							(mid -0.239121 -0.264521)
							(end -0.254 -0.2286)
						)
						(arc
							(start -0.254 0.2286)
							(mid -0.239121 0.264521)
							(end -0.2032 0.2794)
						)
						(arc
							(start 0.2032 0.2794)
							(mid 0.239121 0.264521)
							(end 0.254 0.2286)
						)
						(arc
							(start 0.254 -0.2286)
							(mid 0.239121 -0.264521)
							(end 0.2032 -0.2794)
						)
					)
					(width 0)
					(fill yes)
				)
			)
		)
		(pad "2" smd custom
			(at 0 0.4318 90)
			(size 0.127 0.127)
			(layers "F.Cu" "F.Mask" "F.Paste")
			(net "GND")
			(options
				(clearance outline)
				(anchor circle)
			)
			(primitives
				(gr_poly
					(pts
						(arc
							(start -0.2032 -0.2794)
							(mid -0.239121 -0.264521)
							(end -0.254 -0.2286)
						)
						(arc
							(start -0.254 0.2286)
							(mid -0.239121 0.264521)
							(end -0.2032 0.2794)
						)
						(arc
							(start 0.2032 0.2794)
							(mid 0.239121 0.264521)
							(end 0.254 0.2286)
						)
						(arc
							(start 0.254 -0.2286)
							(mid 0.239121 -0.264521)
							(end 0.2032 -0.2794)
						)
					)
					(width 0)
					(fill yes)
				)
			)
		)
	)
	(footprint ""
		(layer "F.Cu")
		(at 128.143 -33.528 90)
		(property "Reference" "R26"
			(at 0 0 90)
			(layer "F.SilkS")
			(hide yes)
			(effects
				(font
					(size 1.27 1.27)
				)
			)
		)
		(property "Value" "4K7R2F-GP"
			(at 0.064008 -3.993896 90)
			(unlocked yes)
			(layer "F.Fab")
			(hide yes)
			(effects
				(font
					(size 1.016 1.016)
					(thickness 0.1524)
				)
			)
		)
		(property "Device Type" "R402H16"
			(at 0.064008 -5.517896 90)
			(unlocked yes)
			(layer "F.Fab")
			(hide yes)
			(effects
				(font
					(size 1.016 1.016)
					(thickness 0.1524)
				)
			)
		)
		(duplicate_pad_numbers_are_jumpers no)
		(fp_rect
			(start -0.381 0.8382)
			(end 0.381 -0.8382)
			(stroke
				(width 0)
				(type default)
			)
			(fill no)
			(layer "F.CrtYd")
		)
		(fp_rect
			(start -0.381 0.8382)
			(end 0.381 -0.8382)
			(stroke
				(width 0)
				(type default)
			)
			(fill no)
			(layer "F.Fab")
		)
		(pad "1" smd custom
			(at 0 -0.4318 90)
			(size 0.127 0.127)
			(layers "F.Cu" "F.Mask" "F.Paste")
			(net "P3V3_STBY")
			(options
				(clearance outline)
				(anchor circle)
			)
			(primitives
				(gr_poly
					(pts
						(arc
							(start -0.2032 -0.2794)
							(mid -0.239121 -0.264521)
							(end -0.254 -0.2286)
						)
						(arc
							(start -0.254 0.2286)
							(mid -0.239121 0.264521)
							(end -0.2032 0.2794)
						)
						(arc
							(start 0.2032 0.2794)
							(mid 0.239121 0.264521)
							(end 0.254 0.2286)
						)
						(arc
							(start 0.254 -0.2286)
							(mid 0.239121 -0.264521)
							(end 0.2032 -0.2794)
						)
					)
					(width 0)
					(fill yes)
				)
			)
		)
		(pad "2" smd custom
			(at 0 0.4318 90)
			(size 0.127 0.127)
			(layers "F.Cu" "F.Mask" "F.Paste")
			(net "SMB_PECI_LV_CLK")
			(options
				(clearance outline)
				(anchor circle)
			)
			(primitives
				(gr_poly
					(pts
						(arc
							(start -0.2032 -0.2794)
							(mid -0.239121 -0.264521)
							(end -0.254 -0.2286)
						)
						(arc
							(start -0.254 0.2286)
							(mid -0.239121 0.264521)
							(end -0.2032 0.2794)
						)
						(arc
							(start 0.2032 0.2794)
							(mid 0.239121 0.264521)
							(end 0.254 0.2286)
						)
						(arc
							(start 0.254 -0.2286)
							(mid 0.239121 -0.264521)
							(end 0.2032 -0.2794)
						)
					)
					(width 0)
					(fill yes)
				)
			)
		)
	)
	(footprint ""
		(layer "F.Cu")
		(at 44.6024 -24.003 90)
		(property "Reference" "TP19"
			(at 0 0 90)
			(layer "F.SilkS")
			(hide yes)
			(effects
				(font
					(size 1.27 1.27)
				)
			)
		)
		(property "Value" "TPAD28-1-GP-U"
			(at 0.0508 -1.9304 90)
			(unlocked yes)
			(layer "F.Fab")
			(hide yes)
			(effects
				(font
					(size 1.016 1.016)
					(thickness 0.1524)
				)
			)
		)
		(property "Device Type" "TPAD28-1-U"
			(at 0.0508 -3.4544 90)
			(unlocked yes)
			(layer "F.Fab")
			(hide yes)
			(effects
				(font
					(size 1.016 1.016)
					(thickness 0.1524)
				)
			)
		)
		(duplicate_pad_numbers_are_jumpers no)
		(fp_poly
			(pts
				(arc
					(start 0 0.3556)
					(mid 0 -0.3556)
					(end 0 0.3556)
				)
			)
			(stroke
				(width 0)
				(type default)
			)
			(fill no)
			(layer "F.CrtYd")
		)
		(fp_poly
			(pts
				(arc
					(start 0 0.9525)
					(mid 0 -0.9525)
					(end 0 0.9525)
				)
			)
			(stroke
				(width 0)
				(type default)
			)
			(fill no)
			(layer "F.Fab")
		)
		(pad "1" smd circle
			(at 0 0 90)
			(size 0.7112 0.7112)
			(layers "F.Cu" "F.Mask" "F.Paste")
			(net "TP_XDP_DFX_PORT_CLK1")
		)
	)
	(footprint ""
		(layer "F.Cu")
		(at 203.962 -68.7324 90)
		(property "Reference" "PC178"
			(at 0 0 90)
			(layer "F.SilkS")
			(hide yes)
			(effects
				(font
					(size 1.27 1.27)
				)
			)
		)
		(property "Value" "SC10U6D3V3MX-GP"
			(at -0.0254 -2.0193 90)
			(unlocked yes)
			(layer "F.Fab")
			(hide yes)
			(effects
				(font
					(size 1.016 1.016)
					(thickness 0.1524)
				)
			)
		)
		(property "Device Type" "C603H38"
			(at -0.0254 -3.5433 90)
			(unlocked yes)
			(layer "F.Fab")
			(hide yes)
			(effects
				(font
					(size 1.016 1.016)
					(thickness 0.1524)
				)
			)
		)
		(duplicate_pad_numbers_are_jumpers no)
		(fp_line
			(start -0.4064 0)
			(end 0.4064 0)
			(stroke
				(width 0.2286)
				(type default)
			)
			(layer "F.SilkS")
		)
		(fp_rect
			(start -0.635 1.1811)
			(end 0.635 -1.1811)
			(stroke
				(width 0)
				(type default)
			)
			(fill no)
			(layer "F.CrtYd")
		)
		(fp_rect
			(start -0.635 1.1811)
			(end 0.635 -1.1811)
			(stroke
				(width 0)
				(type default)
			)
			(fill no)
			(layer "F.Fab")
		)
		(pad "1" smd custom
			(at 0 -0.6604 90)
			(size 0.19685 0.19685)
			(layers "F.Cu" "F.Mask" "F.Paste")
			(net "PV_VDDR")
			(options
				(clearance outline)
				(anchor circle)
			)
			(primitives
				(gr_poly
					(pts
						(arc
							(start 0.508 -0.2921)
							(mid 0.478242 -0.363942)
							(end 0.4064 -0.3937)
						)
						(arc
							(start -0.4064 -0.3937)
							(mid -0.478242 -0.363942)
							(end -0.508 -0.2921)
						)
						(arc
							(start -0.508 0.2921)
							(mid -0.478242 0.363942)
							(end -0.4064 0.3937)
						)
						(arc
							(start 0.4064 0.3937)
							(mid 0.478242 0.363942)
							(end 0.508 0.2921)
						)
					)
					(width 0)
					(fill yes)
				)
			)
		)
		(pad "2" smd custom
			(at 0 0.6604 90)
			(size 0.19685 0.19685)
			(layers "F.Cu" "F.Mask" "F.Paste")
			(net "GND")
			(options
				(clearance outline)
				(anchor circle)
			)
			(primitives
				(gr_poly
					(pts
						(arc
							(start 0.508 -0.2921)
							(mid 0.478242 -0.363942)
							(end 0.4064 -0.3937)
						)
						(arc
							(start -0.4064 -0.3937)
							(mid -0.478242 -0.363942)
							(end -0.508 -0.2921)
						)
						(arc
							(start -0.508 0.2921)
							(mid -0.478242 0.363942)
							(end -0.4064 0.3937)
						)
						(arc
							(start 0.4064 0.3937)
							(mid 0.478242 0.363942)
							(end 0.508 0.2921)
						)
					)
					(width 0)
					(fill yes)
				)
			)
		)
	)
	(footprint ""
		(layer "F.Cu")
		(at 20.066 -33.2486 180)
		(property "Reference" "PR198"
			(at 0 0 180)
			(layer "F.SilkS")
			(hide yes)
			(effects
				(font
					(size 1.27 1.27)
				)
			)
		)
		(property "Value" "44K2R2F-1-GP"
			(at 1.7907 -1.1176 180)
			(unlocked yes)
			(layer "F.Fab")
			(hide yes)
			(effects
				(font
					(size 1.016 1.016)
					(thickness 0.1524)
				)
			)
		)
		(property "Device Type" "R402H16"
			(at 1.7907 -2.6416 180)
			(unlocked yes)
			(layer "F.Fab")
			(hide yes)
			(effects
				(font
					(size 1.016 1.016)
					(thickness 0.1524)
				)
			)
		)
		(duplicate_pad_numbers_are_jumpers no)
		(fp_rect
			(start -0.381 0.8382)
			(end 0.381 -0.8382)
			(stroke
				(width 0)
				(type default)
			)
			(fill no)
			(layer "F.CrtYd")
		)
		(fp_rect
			(start -0.381 0.8382)
			(end 0.381 -0.8382)
			(stroke
				(width 0)
				(type default)
			)
			(fill no)
			(layer "F.Fab")
		)
		(pad "1" smd custom
			(at 0 -0.4318 180)
			(size 0.127 0.127)
			(layers "F.Cu" "F.Mask" "F.Paste")
			(net "P3V3_STBY_VFB")
			(options
				(clearance outline)
				(anchor circle)
			)
			(primitives
				(gr_poly
					(pts
						(arc
							(start -0.2032 -0.2794)
							(mid -0.239121 -0.264521)
							(end -0.254 -0.2286)
						)
						(arc
							(start -0.254 0.2286)
							(mid -0.239121 0.264521)
							(end -0.2032 0.2794)
						)
						(arc
							(start 0.2032 0.2794)
							(mid 0.239121 0.264521)
							(end 0.254 0.2286)
						)
						(arc
							(start 0.254 -0.2286)
							(mid 0.239121 -0.264521)
							(end 0.2032 -0.2794)
						)
					)
					(width 0)
					(fill yes)
				)
			)
		)
		(pad "2" smd custom
			(at 0 0.4318 180)
			(size 0.127 0.127)
			(layers "F.Cu" "F.Mask" "F.Paste")
			(net "P3V3_STBY_VFB_R")
			(options
				(clearance outline)
				(anchor circle)
			)
			(primitives
				(gr_poly
					(pts
						(arc
							(start -0.2032 -0.2794)
							(mid -0.239121 -0.264521)
							(end -0.254 -0.2286)
						)
						(arc
							(start -0.254 0.2286)
							(mid -0.239121 0.264521)
							(end -0.2032 0.2794)
						)
						(arc
							(start 0.2032 0.2794)
							(mid 0.239121 0.264521)
							(end 0.254 0.2286)
						)
						(arc
							(start 0.254 -0.2286)
							(mid 0.239121 -0.264521)
							(end 0.2032 -0.2794)
						)
					)
					(width 0)
					(fill yes)
				)
			)
		)
	)
	(footprint ""
		(layer "F.Cu")
		(at 183.388 -53.848 180)
		(property "Reference" "R202"
			(at 0 0 180)
			(layer "F.SilkS")
			(hide yes)
			(effects
				(font
					(size 1.27 1.27)
				)
			)
		)
		(property "Value" "2D2R2J-GP"
			(at 0.064008 -3.993896 180)
			(unlocked yes)
			(layer "F.Fab")
			(hide yes)
			(effects
				(font
					(size 1.016 1.016)
					(thickness 0.1524)
				)
			)
		)
		(property "Device Type" "R402H16"
			(at 0.064008 -5.517896 180)
			(unlocked yes)
			(layer "F.Fab")
			(hide yes)
			(effects
				(font
					(size 1.016 1.016)
					(thickness 0.1524)
				)
			)
		)
		(duplicate_pad_numbers_are_jumpers no)
		(fp_rect
			(start -0.381 0.8382)
			(end 0.381 -0.8382)
			(stroke
				(width 0)
				(type default)
			)
			(fill no)
			(layer "F.CrtYd")
		)
		(fp_rect
			(start -0.381 0.8382)
			(end 0.381 -0.8382)
			(stroke
				(width 0)
				(type default)
			)
			(fill no)
			(layer "F.Fab")
		)
		(pad "1" smd custom
			(at 0 -0.4318 180)
			(size 0.127 0.127)
			(layers "F.Cu" "F.Mask" "F.Paste")
			(net "PV_VDDR_VREF_A_FB")
			(options
				(clearance outline)
				(anchor circle)
			)
			(primitives
				(gr_poly
					(pts
						(arc
							(start -0.2032 -0.2794)
							(mid -0.239121 -0.264521)
							(end -0.254 -0.2286)
						)
						(arc
							(start -0.254 0.2286)
							(mid -0.239121 0.264521)
							(end -0.2032 0.2794)
						)
						(arc
							(start 0.2032 0.2794)
							(mid 0.239121 0.264521)
							(end 0.254 0.2286)
						)
						(arc
							(start 0.254 -0.2286)
							(mid 0.239121 -0.264521)
							(end 0.2032 -0.2794)
						)
					)
					(width 0)
					(fill yes)
				)
			)
		)
		(pad "2" smd custom
			(at 0 0.4318 180)
			(size 0.127 0.127)
			(layers "F.Cu" "F.Mask" "F.Paste")
			(net "PV_VDDR_VREF_A")
			(options
				(clearance outline)
				(anchor circle)
			)
			(primitives
				(gr_poly
					(pts
						(arc
							(start -0.2032 -0.2794)
							(mid -0.239121 -0.264521)
							(end -0.254 -0.2286)
						)
						(arc
							(start -0.254 0.2286)
							(mid -0.239121 0.264521)
							(end -0.2032 0.2794)
						)
						(arc
							(start 0.2032 0.2794)
							(mid 0.239121 0.264521)
							(end 0.254 0.2286)
						)
						(arc
							(start 0.254 -0.2286)
							(mid 0.239121 -0.264521)
							(end 0.2032 -0.2794)
						)
					)
					(width 0)
					(fill yes)
				)
			)
		)
	)
)
